# T6G (Grand Teton) — schematic netlist excerpt (pin names and nets, part order shuffled) for the footprints in the layout excerpt that follows; sources: Cadence DE-HDL packaged netlist, KiCad conversion of 04192023_DAF0TMB3IC0_F0TG_MB_C_brd_V02_OCP.brd

R6177  Q_RES  1K 1% CHIP  pkg 0402LF  page 112 : A = P3V3_AUX ; B = FM_P2E_BUF2_SD_TH
R6057  Q_RES  0 5% CHIP  pkg 0402LF  page 139 : A = RST_PERST_OCP_V3_2_BUF2_N ; B = RST_PERST1_OCP_V3_2_N

(kicad_pcb
	(version 20260206)
	(generator "pcbnew")
	(generator_version "10.0")
	(general
		(thickness 1.6)
		(legacy_teardrops no)
	)
	(paper "A4")
	(title_block
		(title "04192023_DAF0TMB3IC0_F0TG_MB_C_brd_V02_OCP.brd")
		(comment 1 "Grand Teton / footprints 1215-1216 of 8354")
	)
	(layers
		(0 "F.Cu" signal "TOP")
		(4 "In1.Cu" signal "GND")
		(6 "In2.Cu" signal "IN1")
		(8 "In3.Cu" signal "GND1")
		(10 "In4.Cu" signal "IN2")
		(12 "In5.Cu" signal "GND2")
		(14 "In6.Cu" signal "IN3")
		(16 "In7.Cu" signal "GND3")
		(18 "In8.Cu" signal "VCC")
		(20 "In9.Cu" signal "VCC1")
		(22 "In10.Cu" signal "GND4")
		(24 "In11.Cu" signal "IN4")
		(26 "In12.Cu" signal "GND5")
		(28 "In13.Cu" signal "IN5")
		(30 "In14.Cu" signal "GND6")
		(32 "In15.Cu" signal "IN6")
		(34 "In16.Cu" signal "GND7")
		(2 "B.Cu" signal "BOTTOM")
		(9 "F.Adhes" user "F.Adhesive")
		(11 "B.Adhes" user "B.Adhesive")
		(13 "F.Paste" user "Package Geometry/Pastemask Top")
		(15 "B.Paste" user "Package Geometry/Pastemask Bottom")
		(5 "F.SilkS" user "Ref Des/Silkscreen Top")
		(7 "B.SilkS" user "Ref Des/Silkscreen Bottom")
		(1 "F.Mask" user "Board Geometry/Soldermask Top")
		(3 "B.Mask" user "Board Geometry/Soldermask Bottom")
		(17 "Dwgs.User" user "User.Drawings")
		(19 "Cmts.User" user "User.Comments")
		(21 "Eco1.User" user "User.Eco1")
		(23 "Eco2.User" user "User.Eco2")
		(25 "Edge.Cuts" user "Board Geometry/Outline")
		(27 "Margin" user)
		(31 "F.CrtYd" user "Package Geometry/Place Bound Top")
		(29 "B.CrtYd" user "Package Geometry/Place Bound Bottom")
		(35 "F.Fab" user "Ref Des/Assembly Top")
		(33 "B.Fab" user "Ref Des/Assembly Bottom")
	)
	(footprint ""
		(layer "F.Cu")
		(at 14.078458 -418.690298 90)
		(property "Reference" "R6177"
			(at 0 0 90)
			(layer "F.SilkS")
			(hide yes)
			(effects
				(font
					(size 1.27 1.27)
				)
			)
		)
		(property "Value" ""
			(at 0 0 90)
			(layer "F.Fab")
			(effects
				(font
					(size 1.27 1.27)
				)
			)
		)
		(duplicate_pad_numbers_are_jumpers no)
		(fp_line
			(start 0.7874 -0.4064)
			(end 0.7874 0.4064)
			(stroke
				(width 0.1524)
				(type default)
			)
			(layer "F.SilkS")
		)
		(fp_line
			(start -0.7874 -0.4064)
			(end 0.7874 -0.4064)
			(stroke
				(width 0.1524)
				(type default)
			)
			(layer "F.SilkS")
		)
		(fp_line
			(start 0.7874 0.4064)
			(end -0.7874 0.4064)
			(stroke
				(width 0.1524)
				(type default)
			)
			(layer "F.SilkS")
		)
		(fp_line
			(start -0.7874 0.4064)
			(end -0.7874 -0.4064)
			(stroke
				(width 0.1524)
				(type default)
			)
			(layer "F.SilkS")
		)
		(fp_line
			(start -0.12065 -0.305054)
			(end -0.12065 -0.2794)
			(stroke
				(width 0.1)
				(type default)
			)
			(layer "F.Fab")
		)
		(fp_line
			(start -0.67945 -0.305054)
			(end -0.12065 -0.305054)
			(stroke
				(width 0.1)
				(type default)
			)
			(layer "F.Fab")
		)
		(fp_line
			(start 0.67945 -0.3048)
			(end 0.67945 0.3048)
			(stroke
				(width 0.1)
				(type default)
			)
			(layer "F.Fab")
		)
		(fp_line
			(start 0.12065 -0.3048)
			(end 0.67945 -0.3048)
			(stroke
				(width 0.1)
				(type default)
			)
			(layer "F.Fab")
		)
		(fp_line
			(start 0.12065 -0.2794)
			(end 0.12065 -0.3048)
			(stroke
				(width 0.1)
				(type default)
			)
			(layer "F.Fab")
		)
		(fp_line
			(start -0.12065 -0.2794)
			(end 0.12065 -0.2794)
			(stroke
				(width 0.1)
				(type default)
			)
			(layer "F.Fab")
		)
		(fp_line
			(start 0.120396 0.2794)
			(end -0.12065 0.2794)
			(stroke
				(width 0.1)
				(type default)
			)
			(layer "F.Fab")
		)
		(fp_line
			(start -0.12065 0.2794)
			(end -0.12065 0.3048)
			(stroke
				(width 0.1)
				(type default)
			)
			(layer "F.Fab")
		)
		(fp_line
			(start 0.67945 0.3048)
			(end 0.120396 0.3048)
			(stroke
				(width 0.1)
				(type default)
			)
			(layer "F.Fab")
		)
		(fp_line
			(start 0.120396 0.3048)
			(end 0.120396 0.2794)
			(stroke
				(width 0.1)
				(type default)
			)
			(layer "F.Fab")
		)
		(fp_line
			(start -0.12065 0.3048)
			(end -0.67945 0.3048)
			(stroke
				(width 0.1)
				(type default)
			)
			(layer "F.Fab")
		)
		(fp_line
			(start -0.67945 0.3048)
			(end -0.67945 -0.305054)
			(stroke
				(width 0.1)
				(type default)
			)
			(layer "F.Fab")
		)
		(pad "1" smd circle
			(at -0.40005 0 90)
			(size 0 0)
			(layers "F.Cu" "F.Mask" "F.Paste")
			(net "P3V3_AUX")
		)
		(pad "2" smd circle
			(at 0.40005 0 90)
			(size 0 0)
			(layers "F.Cu" "F.Mask" "F.Paste")
			(net "FM_P2E_BUF2_SD_TH")
		)
	)
	(footprint ""
		(layer "F.Cu")
		(at 83.222084 -39.65448 180)
		(property "Reference" "R6057"
			(at 0 0 180)
			(layer "F.SilkS")
			(hide yes)
			(effects
				(font
					(size 1.27 1.27)
				)
			)
		)
		(property "Value" ""
			(at 0 0 180)
			(layer "F.Fab")
			(effects
				(font
					(size 1.27 1.27)
				)
			)
		)
		(duplicate_pad_numbers_are_jumpers no)
		(fp_line
			(start 0.7874 0.4064)
			(end -0.7874 0.4064)
			(stroke
				(width 0.1524)
				(type default)
			)
			(layer "F.SilkS")
		)
		(fp_line
			(start 0.7874 -0.4064)
			(end 0.7874 0.4064)
			(stroke
				(width 0.1524)
				(type default)
			)
			(layer "F.SilkS")
		)
		(fp_line
			(start -0.7874 0.4064)
			(end -0.7874 -0.4064)
			(stroke
				(width 0.1524)
				(type default)
			)
			(layer "F.SilkS")
		)
		(fp_line
			(start -0.7874 -0.4064)
			(end 0.7874 -0.4064)
			(stroke
				(width 0.1524)
				(type default)
			)
			(layer "F.SilkS")
		)
		(fp_line
			(start 0.67945 0.3048)
			(end 0.120396 0.3048)
			(stroke
				(width 0.1)
				(type default)
			)
			(layer "F.Fab")
		)
		(fp_line
			(start 0.67945 -0.3048)
			(end 0.67945 0.3048)
			(stroke
				(width 0.1)
				(type default)
			)
			(layer "F.Fab")
		)
		(fp_line
			(start 0.12065 -0.2794)
			(end 0.12065 -0.3048)
			(stroke
				(width 0.1)
				(type default)
			)
			(layer "F.Fab")
		)
		(fp_line
			(start 0.12065 -0.3048)
			(end 0.67945 -0.3048)
			(stroke
				(width 0.1)
				(type default)
			)
			(layer "F.Fab")
		)
		(fp_line
			(start 0.120396 0.3048)
			(end 0.120396 0.2794)
			(stroke
				(width 0.1)
				(type default)
			)
			(layer "F.Fab")
		)
		(fp_line
			(start 0.120396 0.2794)
			(end -0.12065 0.2794)
			(stroke
				(width 0.1)
				(type default)
			)
			(layer "F.Fab")
		)
		(fp_line
			(start -0.12065 0.3048)
			(end -0.67945 0.3048)
			(stroke
				(width 0.1)
				(type default)
			)
			(layer "F.Fab")
		)
		(fp_line
			(start -0.12065 0.2794)
			(end -0.12065 0.3048)
			(stroke
				(width 0.1)
				(type default)
			)
			(layer "F.Fab")
		)
		(fp_line
			(start -0.12065 -0.2794)
			(end 0.12065 -0.2794)
			(stroke
				(width 0.1)
				(type default)
			)
			(layer "F.Fab")
		)
		(fp_line
			(start -0.12065 -0.305054)
			(end -0.12065 -0.2794)
			(stroke
				(width 0.1)
				(type default)
			)
			(layer "F.Fab")
		)
		(fp_line
			(start -0.67945 0.3048)
			(end -0.67945 -0.305054)
			(stroke
				(width 0.1)
				(type default)
			)
			(layer "F.Fab")
		)
		(fp_line
			(start -0.67945 -0.305054)
			(end -0.12065 -0.305054)
			(stroke
				(width 0.1)
				(type default)
			)
			(layer "F.Fab")
		)
		(pad "1" smd circle
			(at -0.40005 0 180)
			(size 0 0)
			(layers "F.Cu" "F.Mask" "F.Paste")
			(net "RST_PERST_OCP_V3_2_BUF2_N")
		)
		(pad "2" smd circle
			(at 0.40005 0 180)
			(size 0 0)
			(layers "F.Cu" "F.Mask" "F.Paste")
			(net "RST_PERST1_OCP_V3_2_N")
		)
	)
)
